(kicad_pcb
	(version 20260206)
	(generator "pcbnew")
	(generator_version "10.0")
	(general
		(thickness 1.6)
		(legacy_teardrops no)
	)
	(paper "A4")
	(title_block
		(title "Bryce Canyon_SCC_16316-1_OCP.brd")
		(comment 1 "Bryce Canyon / footprints 776-783 of 1561")
	)
	(layers
		(0 "F.Cu" signal "TOP")
		(4 "In1.Cu" signal "L2GND")
		(6 "In2.Cu" signal "L3")
		(8 "In3.Cu" signal "L4VCC")
		(10 "In4.Cu" signal "L5VCC")
		(12 "In5.Cu" signal "L6")
		(14 "In6.Cu" signal "L7GND")
		(2 "B.Cu" signal "BOTTOM")
		(9 "F.Adhes" user "F.Adhesive")
		(11 "B.Adhes" user "B.Adhesive")
		(13 "F.Paste" user "Package Geometry/Pastemask Top")
		(15 "B.Paste" user "Package Geometry/Pastemask Bottom")
		(5 "F.SilkS" user "Ref Des/Silkscreen Top")
		(7 "B.SilkS" user "Ref Des/Silkscreen Bottom")
		(1 "F.Mask" user "Board Geometry/Soldermask Top")
		(3 "B.Mask" user "Board Geometry/Soldermask Bottom")
		(17 "Dwgs.User" user "User.Drawings")
		(19 "Cmts.User" user "User.Comments")
		(21 "Eco1.User" user "User.Eco1")
		(23 "Eco2.User" user "User.Eco2")
		(25 "Edge.Cuts" user "Board Geometry/Outline")
		(27 "Margin" user)
		(31 "F.CrtYd" user "Package Geometry/Place Bound Top")
		(29 "B.CrtYd" user "Package Geometry/Place Bound Bottom")
		(35 "F.Fab" user "Ref Des/Assembly Top")
		(33 "B.Fab" user "Ref Des/Assembly Bottom")
	)
	(footprint ""
		(layer "B.Cu")
		(at 96.497394 -54.557168 90)
		(property "Reference" "C95"
			(at 0 0 90)
			(layer "B.SilkS")
			(hide yes)
			(effects
				(font
					(size 1.27 1.27)
				)
				(justify mirror)
			)
		)
		(property "Value" "SCD01U16V1KX-GP"
			(at 2.8321 -1.7399 90)
			(unlocked yes)
			(layer "B.Fab")
			(hide yes)
			(effects
				(font
					(size 1.016 1.016)
					(thickness 0.1524)
				)
				(justify mirror)
			)
		)
		(property "Device Type" "C0201H13"
			(at 2.8321 -3.2639 90)
			(unlocked yes)
			(layer "B.Fab")
			(hide yes)
			(effects
				(font
					(size 1.016 1.016)
					(thickness 0.1524)
				)
				(justify mirror)
			)
		)
		(duplicate_pad_numbers_are_jumpers no)
		(fp_rect
			(start 0.2794 0.6477)
			(end -0.2794 -0.6477)
			(stroke
				(width 0)
				(type default)
			)
			(fill no)
			(layer "B.CrtYd")
		)
		(fp_rect
			(start 0.2794 0.6477)
			(end -0.2794 -0.6477)
			(stroke
				(width 0)
				(type default)
			)
			(fill no)
			(layer "B.Fab")
		)
		(pad "1" smd custom
			(at 0 -0.2794 270)
			(size 0.0762 0.0762)
			(layers "B.Cu" "B.Mask" "B.Paste")
			(net "PHY_DPB_TO_SCC_12_DP")
			(options
				(clearance outline)
				(anchor circle)
			)
			(primitives
				(gr_poly
					(pts
						(arc
							(start 0.1524 0.127)
							(mid 0.137521 0.162921)
							(end 0.1016 0.1778)
						)
						(arc
							(start -0.1016 0.1778)
							(mid -0.137521 0.162921)
							(end -0.1524 0.127)
						)
						(arc
							(start -0.1524 -0.127)
							(mid -0.137521 -0.162921)
							(end -0.1016 -0.1778)
						)
						(arc
							(start 0.1016 -0.1778)
							(mid 0.137521 -0.162921)
							(end 0.1524 -0.127)
						)
					)
					(width 0)
					(fill yes)
				)
			)
		)
		(pad "2" smd custom
			(at 0 0.2794 270)
			(size 0.0762 0.0762)
			(layers "B.Cu" "B.Mask" "B.Paste")
			(net "PHY_DPB_TO_SCC_C_12_DP")
			(options
				(clearance outline)
				(anchor circle)
			)
			(primitives
				(gr_poly
					(pts
						(arc
							(start 0.1524 0.127)
							(mid 0.137521 0.162921)
							(end 0.1016 0.1778)
						)
						(arc
							(start -0.1016 0.1778)
							(mid -0.137521 0.162921)
							(end -0.1524 0.127)
						)
						(arc
							(start -0.1524 -0.127)
							(mid -0.137521 -0.162921)
							(end -0.1016 -0.1778)
						)
						(arc
							(start 0.1016 -0.1778)
							(mid 0.137521 -0.162921)
							(end 0.1524 -0.127)
						)
					)
					(width 0)
					(fill yes)
				)
			)
		)
	)
	(footprint ""
		(layer "B.Cu")
		(at 179.441348 -41.887902 90)
		(property "Reference" "C411"
			(at 0 0 90)
			(layer "B.SilkS")
			(hide yes)
			(effects
				(font
					(size 1.27 1.27)
				)
				(justify mirror)
			)
		)
		(property "Value" "SC1U6D3V1MX-GP"
			(at -1.9177 2.0193 90)
			(unlocked yes)
			(layer "B.Fab")
			(hide yes)
			(effects
				(font
					(size 1.016 1.016)
					(thickness 0.1524)
				)
				(justify mirror)
			)
		)
		(property "Device Type" "C0201H14"
			(at -1.9177 0.4953 90)
			(unlocked yes)
			(layer "B.Fab")
			(hide yes)
			(effects
				(font
					(size 1.016 1.016)
					(thickness 0.1524)
				)
				(justify mirror)
			)
		)
		(duplicate_pad_numbers_are_jumpers no)
		(fp_rect
			(start 0.1524 0.3048)
			(end -0.1524 -0.3048)
			(stroke
				(width 0)
				(type default)
			)
			(fill no)
			(layer "B.CrtYd")
		)
		(fp_poly
			(pts
				(xy 0.2794 0.6477) (xy 0.2794 -0.6477) (xy -0.2794 -0.6477) (xy -0.2794 -0.1905) (xy -0.1524 -0.1905)
				(xy -0.1524 -0.3048) (xy 0.1524 -0.3048) (xy 0.1524 0.3048) (xy -0.1524 0.3048) (xy -0.1524 -0.1778)
				(xy -0.2794 -0.1778) (xy -0.2794 0.6477)
			)
			(stroke
				(width 0)
				(type default)
			)
			(fill no)
			(layer "B.CrtYd")
		)
		(fp_rect
			(start 0.2794 0.6477)
			(end -0.2794 -0.6477)
			(stroke
				(width 0)
				(type default)
			)
			(fill no)
			(layer "B.Fab")
		)
		(pad "1" smd custom
			(at 0 -0.2794 270)
			(size 0.0762 0.0762)
			(layers "B.Cu" "B.Mask" "B.Paste")
			(net "P0V975")
			(options
				(clearance outline)
				(anchor circle)
			)
			(primitives
				(gr_poly
					(pts
						(arc
							(start 0.1524 0.127)
							(mid 0.137521 0.162921)
							(end 0.1016 0.1778)
						)
						(arc
							(start -0.1016 0.1778)
							(mid -0.137521 0.162921)
							(end -0.1524 0.127)
						)
						(arc
							(start -0.1524 -0.127)
							(mid -0.137521 -0.162921)
							(end -0.1016 -0.1778)
						)
						(arc
							(start 0.1016 -0.1778)
							(mid 0.137521 -0.162921)
							(end 0.1524 -0.127)
						)
					)
					(width 0)
					(fill yes)
				)
			)
		)
		(pad "2" smd custom
			(at 0 0.2794 270)
			(size 0.0762 0.0762)
			(layers "B.Cu" "B.Mask" "B.Paste")
			(net "GND")
			(options
				(clearance outline)
				(anchor circle)
			)
			(primitives
				(gr_poly
					(pts
						(arc
							(start 0.1524 0.127)
							(mid 0.137521 0.162921)
							(end 0.1016 0.1778)
						)
						(arc
							(start -0.1016 0.1778)
							(mid -0.137521 0.162921)
							(end -0.1524 0.127)
						)
						(arc
							(start -0.1524 -0.127)
							(mid -0.137521 -0.162921)
							(end -0.1016 -0.1778)
						)
						(arc
							(start 0.1016 -0.1778)
							(mid 0.137521 -0.162921)
							(end 0.1524 -0.127)
						)
					)
					(width 0)
					(fill yes)
				)
			)
		)
	)
	(footprint ""
		(layer "B.Cu")
		(at 81.733898 -70.40118)
		(property "Reference" "C516"
			(at 0 0 0)
			(layer "B.SilkS")
			(hide yes)
			(effects
				(font
					(size 1.27 1.27)
				)
				(justify mirror)
			)
		)
		(property "Value" "SCD1U16V2KX-3GP"
			(at -1.1811 -2.7051 0)
			(unlocked yes)
			(layer "B.Fab")
			(hide yes)
			(effects
				(font
					(size 1.016 1.016)
					(thickness 0.1524)
				)
				(justify mirror)
			)
		)
		(property "Device Type" "C402H22"
			(at -1.1811 -4.2291 0)
			(unlocked yes)
			(layer "B.Fab")
			(hide yes)
			(effects
				(font
					(size 1.016 1.016)
					(thickness 0.1524)
				)
				(justify mirror)
			)
		)
		(duplicate_pad_numbers_are_jumpers no)
		(fp_rect
			(start 0.4318 0.9525)
			(end -0.4318 -0.9525)
			(stroke
				(width 0)
				(type default)
			)
			(fill no)
			(layer "B.CrtYd")
		)
		(fp_rect
			(start 0.4318 0.9525)
			(end -0.4318 -0.9525)
			(stroke
				(width 0)
				(type default)
			)
			(fill no)
			(layer "B.Fab")
		)
		(pad "1" smd custom
			(at 0 -0.4445 180)
			(size 0.1524 0.1524)
			(layers "B.Cu" "B.Mask" "B.Paste")
			(net "P3V3")
			(options
				(clearance outline)
				(anchor circle)
			)
			(primitives
				(gr_poly
					(pts
						(arc
							(start 0.3048 0.2032)
							(mid 0.275042 0.275042)
							(end 0.2032 0.3048)
						)
						(arc
							(start -0.2032 0.3048)
							(mid -0.275042 0.275042)
							(end -0.3048 0.2032)
						)
						(arc
							(start -0.3048 -0.2032)
							(mid -0.275042 -0.275042)
							(end -0.2032 -0.3048)
						)
						(arc
							(start 0.2032 -0.3048)
							(mid 0.275042 -0.275042)
							(end 0.3048 -0.2032)
						)
					)
					(width 0)
					(fill yes)
				)
			)
		)
		(pad "2" smd custom
			(at 0 0.4445 180)
			(size 0.1524 0.1524)
			(layers "B.Cu" "B.Mask" "B.Paste")
			(net "GND")
			(options
				(clearance outline)
				(anchor circle)
			)
			(primitives
				(gr_poly
					(pts
						(arc
							(start 0.3048 0.2032)
							(mid 0.275042 0.275042)
							(end 0.2032 0.3048)
						)
						(arc
							(start -0.2032 0.3048)
							(mid -0.275042 0.275042)
							(end -0.3048 0.2032)
						)
						(arc
							(start -0.3048 -0.2032)
							(mid -0.275042 -0.275042)
							(end -0.2032 -0.3048)
						)
						(arc
							(start 0.2032 -0.3048)
							(mid 0.275042 -0.275042)
							(end 0.3048 -0.2032)
						)
					)
					(width 0)
					(fill yes)
				)
			)
		)
	)
	(footprint ""
		(layer "B.Cu")
		(at 109.499908 -74.499978)
		(property "Reference" "TP37"
			(at 0 0 0)
			(layer "B.SilkS")
			(hide yes)
			(effects
				(font
					(size 1.27 1.27)
				)
				(justify mirror)
			)
		)
		(property "Value" "TPAD28-2-GP"
			(at 0.0127 -1.6637 0)
			(unlocked yes)
			(layer "B.Fab")
			(hide yes)
			(effects
				(font
					(size 1.016 1.016)
					(thickness 0.1524)
				)
				(justify mirror)
			)
		)
		(property "Device Type" "TPAD28"
			(at 0.0127 -3.1877 0)
			(unlocked yes)
			(layer "B.Fab")
			(hide yes)
			(effects
				(font
					(size 1.016 1.016)
					(thickness 0.1524)
				)
				(justify mirror)
			)
		)
		(duplicate_pad_numbers_are_jumpers no)
		(fp_poly
			(pts
				(arc
					(start 0.3556 0)
					(mid -0.3556 0)
					(end 0.3556 0)
				)
			)
			(stroke
				(width 0)
				(type default)
			)
			(fill no)
			(layer "B.CrtYd")
		)
		(fp_poly
			(pts
				(arc
					(start 0.6096 0)
					(mid -0.6096 0)
					(end 0.6096 0)
				)
			)
			(stroke
				(width 0)
				(type default)
			)
			(fill no)
			(layer "B.Fab")
		)
		(pad "1" smd circle
			(at 0 0 180)
			(size 0.7112 0.7112)
			(layers "B.Cu" "B.Mask" "B.Paste")
			(net "JTAG_EXP_TCK")
		)
	)
	(footprint ""
		(layer "B.Cu")
		(at 119.888 -89.535 180)
		(property "Reference" "R375"
			(at 0 0 0)
			(layer "B.SilkS")
			(hide yes)
			(effects
				(font
					(size 1.27 1.27)
				)
				(justify mirror)
			)
		)
		(property "Value" "10KR2F-2-GP"
			(at -0.064008 -3.993896 180)
			(unlocked yes)
			(layer "B.Fab")
			(hide yes)
			(effects
				(font
					(size 1.016 1.016)
					(thickness 0.1524)
				)
				(justify mirror)
			)
		)
		(property "Device Type" "R402H16"
			(at -0.064008 -5.517896 180)
			(unlocked yes)
			(layer "B.Fab")
			(hide yes)
			(effects
				(font
					(size 1.016 1.016)
					(thickness 0.1524)
				)
				(justify mirror)
			)
		)
		(duplicate_pad_numbers_are_jumpers no)
		(fp_line
			(start 0.508 -0.9398)
			(end 0.508 0.9398)
			(stroke
				(width 0.1524)
				(type default)
			)
			(layer "B.SilkS")
		)
		(fp_line
			(start -0.508 -0.9398)
			(end 0.508 -0.9398)
			(stroke
				(width 0.1524)
				(type default)
			)
			(layer "B.SilkS")
		)
		(fp_rect
			(start 0.508 0.9398)
			(end -0.508 -0.9398)
			(stroke
				(width 0)
				(type default)
			)
			(fill no)
			(layer "B.CrtYd")
		)
		(fp_rect
			(start 0.508 0.9398)
			(end -0.508 -0.9398)
			(stroke
				(width 0)
				(type default)
			)
			(fill no)
			(layer "B.Fab")
		)
		(pad "1" smd custom
			(at 0 -0.4445)
			(size 0.1397 0.1397)
			(layers "B.Cu" "B.Mask" "B.Paste")
			(net "COMP_SPARE_0_LS")
			(options
				(clearance outline)
				(anchor circle)
			)
			(primitives
				(gr_poly
					(pts
						(arc
							(start -0.1778 0.2794)
							(mid -0.249642 0.249642)
							(end -0.2794 0.1778)
						)
						(arc
							(start -0.2794 -0.1778)
							(mid -0.249642 -0.249642)
							(end -0.1778 -0.2794)
						)
						(arc
							(start 0.1778 -0.2794)
							(mid 0.249642 -0.249642)
							(end 0.2794 -0.1778)
						)
						(arc
							(start 0.2794 0.1778)
							(mid 0.249642 0.249642)
							(end 0.1778 0.2794)
						)
					)
					(width 0)
					(fill yes)
				)
			)
		)
		(pad "2" smd custom
			(at 0 0.4445)
			(size 0.1397 0.1397)
			(layers "B.Cu" "B.Mask" "B.Paste")
			(net "GND")
			(options
				(clearance outline)
				(anchor circle)
			)
			(primitives
				(gr_poly
					(pts
						(arc
							(start -0.1778 0.2794)
							(mid -0.249642 0.249642)
							(end -0.2794 0.1778)
						)
						(arc
							(start -0.2794 -0.1778)
							(mid -0.249642 -0.249642)
							(end -0.1778 -0.2794)
						)
						(arc
							(start 0.1778 -0.2794)
							(mid 0.249642 -0.249642)
							(end 0.2794 -0.1778)
						)
						(arc
							(start 0.2794 0.1778)
							(mid 0.249642 0.249642)
							(end 0.1778 0.2794)
						)
					)
					(width 0)
					(fill yes)
				)
			)
		)
	)
	(footprint ""
		(layer "B.Cu")
		(at 104.4956 -64.77 180)
		(property "Reference" "C199"
			(at 0 0 0)
			(layer "B.SilkS")
			(hide yes)
			(effects
				(font
					(size 1.27 1.27)
				)
				(justify mirror)
			)
		)
		(property "Value" "SCD1U6D3V1KX-GP"
			(at 2.8321 -1.7399 180)
			(unlocked yes)
			(layer "B.Fab")
			(hide yes)
			(effects
				(font
					(size 1.016 1.016)
					(thickness 0.1524)
				)
				(justify mirror)
			)
		)
		(property "Device Type" "C0201H13"
			(at 2.8321 -3.2639 180)
			(unlocked yes)
			(layer "B.Fab")
			(hide yes)
			(effects
				(font
					(size 1.016 1.016)
					(thickness 0.1524)
				)
				(justify mirror)
			)
		)
		(duplicate_pad_numbers_are_jumpers no)
		(fp_rect
			(start 0.2794 0.6477)
			(end -0.2794 -0.6477)
			(stroke
				(width 0)
				(type default)
			)
			(fill no)
			(layer "B.CrtYd")
		)
		(fp_rect
			(start 0.2794 0.6477)
			(end -0.2794 -0.6477)
			(stroke
				(width 0)
				(type default)
			)
			(fill no)
			(layer "B.Fab")
		)
		(pad "1" smd custom
			(at 0 -0.2794)
			(size 0.0762 0.0762)
			(layers "B.Cu" "B.Mask" "B.Paste")
			(net "SYSPLL_VDDA18")
			(options
				(clearance outline)
				(anchor circle)
			)
			(primitives
				(gr_poly
					(pts
						(arc
							(start 0.1524 0.127)
							(mid 0.137521 0.162921)
							(end 0.1016 0.1778)
						)
						(arc
							(start -0.1016 0.1778)
							(mid -0.137521 0.162921)
							(end -0.1524 0.127)
						)
						(arc
							(start -0.1524 -0.127)
							(mid -0.137521 -0.162921)
							(end -0.1016 -0.1778)
						)
						(arc
							(start 0.1016 -0.1778)
							(mid 0.137521 -0.162921)
							(end 0.1524 -0.127)
						)
					)
					(width 0)
					(fill yes)
				)
			)
		)
		(pad "2" smd custom
			(at 0 0.2794)
			(size 0.0762 0.0762)
			(layers "B.Cu" "B.Mask" "B.Paste")
			(net "GND")
			(options
				(clearance outline)
				(anchor circle)
			)
			(primitives
				(gr_poly
					(pts
						(arc
							(start 0.1524 0.127)
							(mid 0.137521 0.162921)
							(end 0.1016 0.1778)
						)
						(arc
							(start -0.1016 0.1778)
							(mid -0.137521 0.162921)
							(end -0.1524 0.127)
						)
						(arc
							(start -0.1524 -0.127)
							(mid -0.137521 -0.162921)
							(end -0.1016 -0.1778)
						)
						(arc
							(start 0.1016 -0.1778)
							(mid 0.137521 -0.162921)
							(end 0.1524 -0.127)
						)
					)
					(width 0)
					(fill yes)
				)
			)
		)
	)
	(footprint ""
		(layer "B.Cu")
		(at 117.488462 -70.37578 180)
		(property "Reference" "C187"
			(at 0 0 0)
			(layer "B.SilkS")
			(hide yes)
			(effects
				(font
					(size 1.27 1.27)
				)
				(justify mirror)
			)
		)
		(property "Value" "SC1KP25V1KX-GP"
			(at 2.8321 -1.7399 180)
			(unlocked yes)
			(layer "B.Fab")
			(hide yes)
			(effects
				(font
					(size 1.016 1.016)
					(thickness 0.1524)
				)
				(justify mirror)
			)
		)
		(property "Device Type" "C0201H13"
			(at 2.8321 -3.2639 180)
			(unlocked yes)
			(layer "B.Fab")
			(hide yes)
			(effects
				(font
					(size 1.016 1.016)
					(thickness 0.1524)
				)
				(justify mirror)
			)
		)
		(duplicate_pad_numbers_are_jumpers no)
		(fp_rect
			(start 0.2794 0.6477)
			(end -0.2794 -0.6477)
			(stroke
				(width 0)
				(type default)
			)
			(fill no)
			(layer "B.CrtYd")
		)
		(fp_rect
			(start 0.2794 0.6477)
			(end -0.2794 -0.6477)
			(stroke
				(width 0)
				(type default)
			)
			(fill no)
			(layer "B.Fab")
		)
		(pad "1" smd custom
			(at 0 -0.2794)
			(size 0.0762 0.0762)
			(layers "B.Cu" "B.Mask" "B.Paste")
			(net "P0V9")
			(options
				(clearance outline)
				(anchor circle)
			)
			(primitives
				(gr_poly
					(pts
						(arc
							(start 0.1524 0.127)
							(mid 0.137521 0.162921)
							(end 0.1016 0.1778)
						)
						(arc
							(start -0.1016 0.1778)
							(mid -0.137521 0.162921)
							(end -0.1524 0.127)
						)
						(arc
							(start -0.1524 -0.127)
							(mid -0.137521 -0.162921)
							(end -0.1016 -0.1778)
						)
						(arc
							(start 0.1016 -0.1778)
							(mid 0.137521 -0.162921)
							(end 0.1524 -0.127)
						)
					)
					(width 0)
					(fill yes)
				)
			)
		)
		(pad "2" smd custom
			(at 0 0.2794)
			(size 0.0762 0.0762)
			(layers "B.Cu" "B.Mask" "B.Paste")
			(net "GND")
			(options
				(clearance outline)
				(anchor circle)
			)
			(primitives
				(gr_poly
					(pts
						(arc
							(start 0.1524 0.127)
							(mid 0.137521 0.162921)
							(end 0.1016 0.1778)
						)
						(arc
							(start -0.1016 0.1778)
							(mid -0.137521 0.162921)
							(end -0.1524 0.127)
						)
						(arc
							(start -0.1524 -0.127)
							(mid -0.137521 -0.162921)
							(end -0.1016 -0.1778)
						)
						(arc
							(start 0.1016 -0.1778)
							(mid 0.137521 -0.162921)
							(end 0.1524 -0.127)
						)
					)
					(width 0)
					(fill yes)
				)
			)
		)
	)
	(footprint ""
		(layer "B.Cu")
		(at 129.397252 -57.35066 90)
		(property "Reference" "C299"
			(at 0 0 90)
			(layer "B.SilkS")
			(hide yes)
			(effects
				(font
					(size 1.27 1.27)
				)
				(justify mirror)
			)
		)
		(property "Value" "SCD1U6D3V1KX-GP"
			(at 2.8321 -1.7399 90)
			(unlocked yes)
			(layer "B.Fab")
			(hide yes)
			(effects
				(font
					(size 1.016 1.016)
					(thickness 0.1524)
				)
				(justify mirror)
			)
		)
		(property "Device Type" "C0201H13"
			(at 2.8321 -3.2639 90)
			(unlocked yes)
			(layer "B.Fab")
			(hide yes)
			(effects
				(font
					(size 1.016 1.016)
					(thickness 0.1524)
				)
				(justify mirror)
			)
		)
		(duplicate_pad_numbers_are_jumpers no)
		(fp_rect
			(start 0.2794 0.6477)
			(end -0.2794 -0.6477)
			(stroke
				(width 0)
				(type default)
			)
			(fill no)
			(layer "B.CrtYd")
		)
		(fp_rect
			(start 0.2794 0.6477)
			(end -0.2794 -0.6477)
			(stroke
				(width 0)
				(type default)
			)
			(fill no)
			(layer "B.Fab")
		)
		(pad "1" smd custom
			(at 0 -0.2794 270)
			(size 0.0762 0.0762)
			(layers "B.Cu" "B.Mask" "B.Paste")
			(net "GB_VDDA")
			(options
				(clearance outline)
				(anchor circle)
			)
			(primitives
				(gr_poly
					(pts
						(arc
							(start 0.1524 0.127)
							(mid 0.137521 0.162921)
							(end 0.1016 0.1778)
						)
						(arc
							(start -0.1016 0.1778)
							(mid -0.137521 0.162921)
							(end -0.1524 0.127)
						)
						(arc
							(start -0.1524 -0.127)
							(mid -0.137521 -0.162921)
							(end -0.1016 -0.1778)
						)
						(arc
							(start 0.1016 -0.1778)
							(mid 0.137521 -0.162921)
							(end 0.1524 -0.127)
						)
					)
					(width 0)
					(fill yes)
				)
			)
		)
		(pad "2" smd custom
			(at 0 0.2794 270)
			(size 0.0762 0.0762)
			(layers "B.Cu" "B.Mask" "B.Paste")
			(net "GND")
			(options
				(clearance outline)
				(anchor circle)
			)
			(primitives
				(gr_poly
					(pts
						(arc
							(start 0.1524 0.127)
							(mid 0.137521 0.162921)
							(end 0.1016 0.1778)
						)
						(arc
							(start -0.1016 0.1778)
							(mid -0.137521 0.162921)
							(end -0.1524 0.127)
						)
						(arc
							(start -0.1524 -0.127)
							(mid -0.137521 -0.162921)
							(end -0.1016 -0.1778)
						)
						(arc
							(start 0.1016 -0.1778)
							(mid 0.137521 -0.162921)
							(end 0.1524 -0.127)
						)
					)
					(width 0)
					(fill yes)
				)
			)
		)
	)
)
